G04*
G04 #@! TF.GenerationSoftware,Altium Limited,Altium Designer,23.7.1 (13)*
G04*
G04 Layer_Color=32768*
%FSLAX25Y25*%
%MOIN*%
G70*
G04*
G04 #@! TF.SameCoordinates,AF00DCEB-AC48-4C7C-91EA-99F42E284231*
G04*
G04*
G04 #@! TF.FilePolarity,Positive*
G04*
G01*
G75*
M02*
